(kicad_pcb
	(version 20260206)
	(generator "pcbnew")
	(generator_version "10.0")
	(general
		(thickness 1.6)
		(legacy_teardrops no)
	)
	(paper "A4")
	(title_block
		(title "01162023_DA0F0TEBIF0_F0T_Expander_BD_F_brd_V02_OCP.brd")
		(comment 1 "Grand Teton / footprints 4155-4161 of 9728")
	)
	(layers
		(0 "F.Cu" signal "TOP")
		(4 "In1.Cu" signal "GND")
		(6 "In2.Cu" signal "VCC")
		(8 "In3.Cu" signal "VCC1")
		(10 "In4.Cu" signal "GND1")
		(12 "In5.Cu" signal "IN1")
		(14 "In6.Cu" signal "GND2")
		(16 "In7.Cu" signal "IN2")
		(18 "In8.Cu" signal "GND3")
		(20 "In9.Cu" signal "IN3")
		(22 "In10.Cu" signal "GND4")
		(24 "In11.Cu" signal "IN4")
		(26 "In12.Cu" signal "GND5")
		(28 "In13.Cu" signal "IN5")
		(30 "In14.Cu" signal "GND6")
		(32 "In15.Cu" signal "IN6")
		(34 "In16.Cu" signal "GND7")
		(2 "B.Cu" signal "BOTTOM")
		(9 "F.Adhes" user "F.Adhesive")
		(11 "B.Adhes" user "B.Adhesive")
		(13 "F.Paste" user "Package Geometry/Pastemask Top")
		(15 "B.Paste" user "Package Geometry/Pastemask Bottom")
		(5 "F.SilkS" user "Ref Des/Silkscreen Top")
		(7 "B.SilkS" user "Ref Des/Silkscreen Bottom")
		(1 "F.Mask" user "Board Geometry/Soldermask Top")
		(3 "B.Mask" user "Board Geometry/Soldermask Bottom")
		(17 "Dwgs.User" user "User.Drawings")
		(19 "Cmts.User" user "User.Comments")
		(21 "Eco1.User" user "User.Eco1")
		(23 "Eco2.User" user "User.Eco2")
		(25 "Edge.Cuts" user "Board Geometry/Outline")
		(27 "Margin" user)
		(31 "F.CrtYd" user "Package Geometry/Place Bound Top")
		(29 "B.CrtYd" user "Package Geometry/Place Bound Bottom")
		(35 "F.Fab" user "Ref Des/Assembly Top")
		(33 "B.Fab" user "Ref Des/Assembly Bottom")
	)
	(footprint ""
		(layer "F.Cu")
		(at 9.218422 -251.312426 -90)
		(property "Reference" "C4227"
			(at 0 0 270)
			(layer "F.SilkS")
			(hide yes)
			(effects
				(font
					(size 1.27 1.27)
				)
			)
		)
		(property "Value" ""
			(at 0 0 270)
			(layer "F.Fab")
			(effects
				(font
					(size 1.27 1.27)
				)
			)
		)
		(duplicate_pad_numbers_are_jumpers no)
		(fp_line
			(start -1.2954 0.5842)
			(end -1.2954 -0.5842)
			(stroke
				(width 0.1524)
				(type default)
			)
			(layer "F.SilkS")
		)
		(fp_line
			(start 1.2954 0.5842)
			(end -1.2954 0.5842)
			(stroke
				(width 0.1524)
				(type default)
			)
			(layer "F.SilkS")
		)
		(fp_line
			(start -1.2954 -0.5842)
			(end 1.2954 -0.5842)
			(stroke
				(width 0.1524)
				(type default)
			)
			(layer "F.SilkS")
		)
		(fp_line
			(start 1.2954 -0.5842)
			(end 1.2954 0.5842)
			(stroke
				(width 0.1524)
				(type default)
			)
			(layer "F.SilkS")
		)
		(fp_line
			(start -0.8636 0.4572)
			(end -0.8636 0.4064)
			(stroke
				(width 0.1)
				(type default)
			)
			(layer "F.Fab")
		)
		(fp_line
			(start 0.8636 0.4572)
			(end -0.8636 0.4572)
			(stroke
				(width 0.1)
				(type default)
			)
			(layer "F.Fab")
		)
		(fp_line
			(start -1.1938 0.4064)
			(end -1.1938 -0.4064)
			(stroke
				(width 0.1)
				(type default)
			)
			(layer "F.Fab")
		)
		(fp_line
			(start -0.8636 0.4064)
			(end -1.1938 0.4064)
			(stroke
				(width 0.1)
				(type default)
			)
			(layer "F.Fab")
		)
		(fp_line
			(start 0.8636 0.4064)
			(end 0.8636 0.4572)
			(stroke
				(width 0.1)
				(type default)
			)
			(layer "F.Fab")
		)
		(fp_line
			(start 1.1938 0.4064)
			(end 0.8636 0.4064)
			(stroke
				(width 0.1)
				(type default)
			)
			(layer "F.Fab")
		)
		(fp_line
			(start -1.1938 -0.4064)
			(end -0.8636 -0.4064)
			(stroke
				(width 0.1)
				(type default)
			)
			(layer "F.Fab")
		)
		(fp_line
			(start -0.8636 -0.4064)
			(end -0.8636 -0.4572)
			(stroke
				(width 0.1)
				(type default)
			)
			(layer "F.Fab")
		)
		(fp_line
			(start 0.8636 -0.4064)
			(end 1.1938 -0.4064)
			(stroke
				(width 0.1)
				(type default)
			)
			(layer "F.Fab")
		)
		(fp_line
			(start 1.1938 -0.4064)
			(end 1.1938 0.4064)
			(stroke
				(width 0.1)
				(type default)
			)
			(layer "F.Fab")
		)
		(fp_line
			(start -0.8636 -0.4572)
			(end 0.8636 -0.4572)
			(stroke
				(width 0.1)
				(type default)
			)
			(layer "F.Fab")
		)
		(fp_line
			(start 0.8636 -0.4572)
			(end 0.8636 -0.4064)
			(stroke
				(width 0.1)
				(type default)
			)
			(layer "F.Fab")
		)
		(pad "1" smd rect
			(at -0.7366 0 180)
			(size 0.7112 0.8128)
			(layers "F.Cu" "F.Mask" "F.Paste")
			(net "P1V25_SERDES_VDDPLL_PEX0_C1")
		)
		(pad "2" smd rect
			(at 0.7366 0 180)
			(size 0.7112 0.8128)
			(layers "F.Cu" "F.Mask" "F.Paste")
			(net "GND")
		)
	)
	(footprint ""
		(layer "F.Cu")
		(at 374.674384 -250.070874 -90)
		(property "Reference" "R1407"
			(at 0 0 270)
			(layer "F.SilkS")
			(hide yes)
			(effects
				(font
					(size 1.27 1.27)
				)
			)
		)
		(property "Value" ""
			(at 0 0 270)
			(layer "F.Fab")
			(effects
				(font
					(size 1.27 1.27)
				)
			)
		)
		(duplicate_pad_numbers_are_jumpers no)
		(fp_line
			(start -0.7874 0.4064)
			(end -0.7874 -0.4064)
			(stroke
				(width 0.1524)
				(type default)
			)
			(layer "F.SilkS")
		)
		(fp_line
			(start 0.7874 0.4064)
			(end -0.7874 0.4064)
			(stroke
				(width 0.1524)
				(type default)
			)
			(layer "F.SilkS")
		)
		(fp_line
			(start -0.7874 -0.4064)
			(end 0.7874 -0.4064)
			(stroke
				(width 0.1524)
				(type default)
			)
			(layer "F.SilkS")
		)
		(fp_line
			(start 0.7874 -0.4064)
			(end 0.7874 0.4064)
			(stroke
				(width 0.1524)
				(type default)
			)
			(layer "F.SilkS")
		)
		(fp_line
			(start -0.67945 0.3048)
			(end -0.67945 -0.305054)
			(stroke
				(width 0.1)
				(type default)
			)
			(layer "F.Fab")
		)
		(fp_line
			(start -0.12065 0.3048)
			(end -0.67945 0.3048)
			(stroke
				(width 0.1)
				(type default)
			)
			(layer "F.Fab")
		)
		(fp_line
			(start 0.120396 0.3048)
			(end 0.120396 0.2794)
			(stroke
				(width 0.1)
				(type default)
			)
			(layer "F.Fab")
		)
		(fp_line
			(start 0.67945 0.3048)
			(end 0.120396 0.3048)
			(stroke
				(width 0.1)
				(type default)
			)
			(layer "F.Fab")
		)
		(fp_line
			(start -0.12065 0.2794)
			(end -0.12065 0.3048)
			(stroke
				(width 0.1)
				(type default)
			)
			(layer "F.Fab")
		)
		(fp_line
			(start 0.120396 0.2794)
			(end -0.12065 0.2794)
			(stroke
				(width 0.1)
				(type default)
			)
			(layer "F.Fab")
		)
		(fp_line
			(start -0.12065 -0.2794)
			(end 0.12065 -0.2794)
			(stroke
				(width 0.1)
				(type default)
			)
			(layer "F.Fab")
		)
		(fp_line
			(start 0.12065 -0.2794)
			(end 0.12065 -0.3048)
			(stroke
				(width 0.1)
				(type default)
			)
			(layer "F.Fab")
		)
		(fp_line
			(start 0.12065 -0.3048)
			(end 0.67945 -0.3048)
			(stroke
				(width 0.1)
				(type default)
			)
			(layer "F.Fab")
		)
		(fp_line
			(start 0.67945 -0.3048)
			(end 0.67945 0.3048)
			(stroke
				(width 0.1)
				(type default)
			)
			(layer "F.Fab")
		)
		(fp_line
			(start -0.67945 -0.305054)
			(end -0.12065 -0.305054)
			(stroke
				(width 0.1)
				(type default)
			)
			(layer "F.Fab")
		)
		(fp_line
			(start -0.12065 -0.305054)
			(end -0.12065 -0.2794)
			(stroke
				(width 0.1)
				(type default)
			)
			(layer "F.Fab")
		)
		(pad "1" smd circle
			(at -0.40005 0 270)
			(size 0 0)
			(layers "F.Cu" "F.Mask" "F.Paste")
			(net "PEX3_MODE_SEL2")
		)
		(pad "2" smd circle
			(at 0.40005 0 270)
			(size 0 0)
			(layers "F.Cu" "F.Mask" "F.Paste")
			(net "P1V8_PEX")
		)
	)
	(footprint ""
		(layer "F.Cu")
		(at 17.354042 -269.446248)
		(property "Reference" "C4239"
			(at 0 0 0)
			(layer "F.SilkS")
			(hide yes)
			(effects
				(font
					(size 1.27 1.27)
				)
			)
		)
		(property "Value" ""
			(at 0 0 0)
			(layer "F.Fab")
			(effects
				(font
					(size 1.27 1.27)
				)
			)
		)
		(duplicate_pad_numbers_are_jumpers no)
		(fp_line
			(start -0.299974 -0.150114)
			(end 0.299974 -0.150114)
			(stroke
				(width 0.1)
				(type default)
			)
			(layer "F.Fab")
		)
		(fp_line
			(start -0.299974 0.150114)
			(end -0.299974 -0.150114)
			(stroke
				(width 0.1)
				(type default)
			)
			(layer "F.Fab")
		)
		(fp_line
			(start 0.299974 -0.150114)
			(end 0.299974 0.150114)
			(stroke
				(width 0.1)
				(type default)
			)
			(layer "F.Fab")
		)
		(fp_line
			(start 0.299974 0.150114)
			(end -0.299974 0.150114)
			(stroke
				(width 0.1)
				(type default)
			)
			(layer "F.Fab")
		)
		(pad "1" smd rect
			(at -0.2667 0)
			(size 0.3048 0.381)
			(layers "F.Cu" "F.Mask" "F.Paste")
			(net "P1V25_SERDES_VDDPLL_PEX0")
		)
		(pad "2" smd rect
			(at 0.2667 0)
			(size 0.3048 0.381)
			(layers "F.Cu" "F.Mask" "F.Paste")
			(net "GND")
		)
	)
	(footprint ""
		(layer "F.Cu")
		(at 206.623158 -84.675472)
		(property "Reference" "R4302"
			(at 0 0 0)
			(layer "F.SilkS")
			(hide yes)
			(effects
				(font
					(size 1.27 1.27)
				)
			)
		)
		(property "Value" ""
			(at 0 0 0)
			(layer "F.Fab")
			(effects
				(font
					(size 1.27 1.27)
				)
			)
		)
		(duplicate_pad_numbers_are_jumpers no)
		(fp_line
			(start -0.7874 -0.4064)
			(end 0.7874 -0.4064)
			(stroke
				(width 0.1524)
				(type default)
			)
			(layer "F.SilkS")
		)
		(fp_line
			(start -0.7874 0.4064)
			(end -0.7874 -0.4064)
			(stroke
				(width 0.1524)
				(type default)
			)
			(layer "F.SilkS")
		)
		(fp_line
			(start 0.7874 -0.4064)
			(end 0.7874 0.4064)
			(stroke
				(width 0.1524)
				(type default)
			)
			(layer "F.SilkS")
		)
		(fp_line
			(start 0.7874 0.4064)
			(end -0.7874 0.4064)
			(stroke
				(width 0.1524)
				(type default)
			)
			(layer "F.SilkS")
		)
		(fp_line
			(start -0.67945 -0.305054)
			(end -0.12065 -0.305054)
			(stroke
				(width 0.1)
				(type default)
			)
			(layer "F.Fab")
		)
		(fp_line
			(start -0.67945 0.3048)
			(end -0.67945 -0.305054)
			(stroke
				(width 0.1)
				(type default)
			)
			(layer "F.Fab")
		)
		(fp_line
			(start -0.12065 -0.305054)
			(end -0.12065 -0.2794)
			(stroke
				(width 0.1)
				(type default)
			)
			(layer "F.Fab")
		)
		(fp_line
			(start -0.12065 -0.2794)
			(end 0.12065 -0.2794)
			(stroke
				(width 0.1)
				(type default)
			)
			(layer "F.Fab")
		)
		(fp_line
			(start -0.12065 0.2794)
			(end -0.12065 0.3048)
			(stroke
				(width 0.1)
				(type default)
			)
			(layer "F.Fab")
		)
		(fp_line
			(start -0.12065 0.3048)
			(end -0.67945 0.3048)
			(stroke
				(width 0.1)
				(type default)
			)
			(layer "F.Fab")
		)
		(fp_line
			(start 0.120396 0.2794)
			(end -0.12065 0.2794)
			(stroke
				(width 0.1)
				(type default)
			)
			(layer "F.Fab")
		)
		(fp_line
			(start 0.120396 0.3048)
			(end 0.120396 0.2794)
			(stroke
				(width 0.1)
				(type default)
			)
			(layer "F.Fab")
		)
		(fp_line
			(start 0.12065 -0.3048)
			(end 0.67945 -0.3048)
			(stroke
				(width 0.1)
				(type default)
			)
			(layer "F.Fab")
		)
		(fp_line
			(start 0.12065 -0.2794)
			(end 0.12065 -0.3048)
			(stroke
				(width 0.1)
				(type default)
			)
			(layer "F.Fab")
		)
		(fp_line
			(start 0.67945 -0.3048)
			(end 0.67945 0.3048)
			(stroke
				(width 0.1)
				(type default)
			)
			(layer "F.Fab")
		)
		(fp_line
			(start 0.67945 0.3048)
			(end 0.120396 0.3048)
			(stroke
				(width 0.1)
				(type default)
			)
			(layer "F.Fab")
		)
		(pad "1" smd circle
			(at -0.40005 0)
			(size 0 0)
			(layers "F.Cu" "F.Mask" "F.Paste")
			(net "SSD0_LED_R")
		)
		(pad "2" smd circle
			(at 0.40005 0)
			(size 0 0)
			(layers "F.Cu" "F.Mask" "F.Paste")
			(net "SSD0_LED")
		)
	)
	(footprint ""
		(layer "F.Cu")
		(at 124.279152 -59.577986 -90)
		(property "Reference" "R887"
			(at 0 0 270)
			(layer "F.SilkS")
			(hide yes)
			(effects
				(font
					(size 1.27 1.27)
				)
			)
		)
		(property "Value" ""
			(at 0 0 270)
			(layer "F.Fab")
			(effects
				(font
					(size 1.27 1.27)
				)
			)
		)
		(duplicate_pad_numbers_are_jumpers no)
		(fp_line
			(start -0.7874 0.4064)
			(end -0.7874 -0.4064)
			(stroke
				(width 0.1524)
				(type default)
			)
			(layer "F.SilkS")
		)
		(fp_line
			(start 0.7874 0.4064)
			(end -0.7874 0.4064)
			(stroke
				(width 0.1524)
				(type default)
			)
			(layer "F.SilkS")
		)
		(fp_line
			(start -0.7874 -0.4064)
			(end 0.7874 -0.4064)
			(stroke
				(width 0.1524)
				(type default)
			)
			(layer "F.SilkS")
		)
		(fp_line
			(start 0.7874 -0.4064)
			(end 0.7874 0.4064)
			(stroke
				(width 0.1524)
				(type default)
			)
			(layer "F.SilkS")
		)
		(fp_line
			(start -0.67945 0.3048)
			(end -0.67945 -0.305054)
			(stroke
				(width 0.1)
				(type default)
			)
			(layer "F.Fab")
		)
		(fp_line
			(start -0.12065 0.3048)
			(end -0.67945 0.3048)
			(stroke
				(width 0.1)
				(type default)
			)
			(layer "F.Fab")
		)
		(fp_line
			(start 0.120396 0.3048)
			(end 0.120396 0.2794)
			(stroke
				(width 0.1)
				(type default)
			)
			(layer "F.Fab")
		)
		(fp_line
			(start 0.67945 0.3048)
			(end 0.120396 0.3048)
			(stroke
				(width 0.1)
				(type default)
			)
			(layer "F.Fab")
		)
		(fp_line
			(start -0.12065 0.2794)
			(end -0.12065 0.3048)
			(stroke
				(width 0.1)
				(type default)
			)
			(layer "F.Fab")
		)
		(fp_line
			(start 0.120396 0.2794)
			(end -0.12065 0.2794)
			(stroke
				(width 0.1)
				(type default)
			)
			(layer "F.Fab")
		)
		(fp_line
			(start -0.12065 -0.2794)
			(end 0.12065 -0.2794)
			(stroke
				(width 0.1)
				(type default)
			)
			(layer "F.Fab")
		)
		(fp_line
			(start 0.12065 -0.2794)
			(end 0.12065 -0.3048)
			(stroke
				(width 0.1)
				(type default)
			)
			(layer "F.Fab")
		)
		(fp_line
			(start 0.12065 -0.3048)
			(end 0.67945 -0.3048)
			(stroke
				(width 0.1)
				(type default)
			)
			(layer "F.Fab")
		)
		(fp_line
			(start 0.67945 -0.3048)
			(end 0.67945 0.3048)
			(stroke
				(width 0.1)
				(type default)
			)
			(layer "F.Fab")
		)
		(fp_line
			(start -0.67945 -0.305054)
			(end -0.12065 -0.305054)
			(stroke
				(width 0.1)
				(type default)
			)
			(layer "F.Fab")
		)
		(fp_line
			(start -0.12065 -0.305054)
			(end -0.12065 -0.2794)
			(stroke
				(width 0.1)
				(type default)
			)
			(layer "F.Fab")
		)
		(pad "1" smd circle
			(at -0.40005 0 270)
			(size 0 0)
			(layers "F.Cu" "F.Mask" "F.Paste")
			(net "P3V3_SSD4")
		)
		(pad "2" smd circle
			(at 0.40005 0 270)
			(size 0 0)
			(layers "F.Cu" "F.Mask" "F.Paste")
			(net "PWRGD_P3V3_SSD4")
		)
	)
	(footprint ""
		(layer "F.Cu")
		(at 381.254 -205.486)
		(property "Reference" "R4631"
			(at 0 0 0)
			(layer "F.SilkS")
			(hide yes)
			(effects
				(font
					(size 1.27 1.27)
				)
			)
		)
		(property "Value" ""
			(at 0 0 0)
			(layer "F.Fab")
			(effects
				(font
					(size 1.27 1.27)
				)
			)
		)
		(duplicate_pad_numbers_are_jumpers no)
		(fp_line
			(start -0.7874 -0.4064)
			(end 0.7874 -0.4064)
			(stroke
				(width 0.1524)
				(type default)
			)
			(layer "F.SilkS")
		)
		(fp_line
			(start -0.7874 0.4064)
			(end -0.7874 -0.4064)
			(stroke
				(width 0.1524)
				(type default)
			)
			(layer "F.SilkS")
		)
		(fp_line
			(start 0.7874 -0.4064)
			(end 0.7874 0.4064)
			(stroke
				(width 0.1524)
				(type default)
			)
			(layer "F.SilkS")
		)
		(fp_line
			(start 0.7874 0.4064)
			(end -0.7874 0.4064)
			(stroke
				(width 0.1524)
				(type default)
			)
			(layer "F.SilkS")
		)
		(fp_line
			(start -0.67945 -0.305054)
			(end -0.12065 -0.305054)
			(stroke
				(width 0.1)
				(type default)
			)
			(layer "F.Fab")
		)
		(fp_line
			(start -0.67945 0.3048)
			(end -0.67945 -0.305054)
			(stroke
				(width 0.1)
				(type default)
			)
			(layer "F.Fab")
		)
		(fp_line
			(start -0.12065 -0.305054)
			(end -0.12065 -0.2794)
			(stroke
				(width 0.1)
				(type default)
			)
			(layer "F.Fab")
		)
		(fp_line
			(start -0.12065 -0.2794)
			(end 0.12065 -0.2794)
			(stroke
				(width 0.1)
				(type default)
			)
			(layer "F.Fab")
		)
		(fp_line
			(start -0.12065 0.2794)
			(end -0.12065 0.3048)
			(stroke
				(width 0.1)
				(type default)
			)
			(layer "F.Fab")
		)
		(fp_line
			(start -0.12065 0.3048)
			(end -0.67945 0.3048)
			(stroke
				(width 0.1)
				(type default)
			)
			(layer "F.Fab")
		)
		(fp_line
			(start 0.120396 0.2794)
			(end -0.12065 0.2794)
			(stroke
				(width 0.1)
				(type default)
			)
			(layer "F.Fab")
		)
		(fp_line
			(start 0.120396 0.3048)
			(end 0.120396 0.2794)
			(stroke
				(width 0.1)
				(type default)
			)
			(layer "F.Fab")
		)
		(fp_line
			(start 0.12065 -0.3048)
			(end 0.67945 -0.3048)
			(stroke
				(width 0.1)
				(type default)
			)
			(layer "F.Fab")
		)
		(fp_line
			(start 0.12065 -0.2794)
			(end 0.12065 -0.3048)
			(stroke
				(width 0.1)
				(type default)
			)
			(layer "F.Fab")
		)
		(fp_line
			(start 0.67945 -0.3048)
			(end 0.67945 0.3048)
			(stroke
				(width 0.1)
				(type default)
			)
			(layer "F.Fab")
		)
		(fp_line
			(start 0.67945 0.3048)
			(end 0.120396 0.3048)
			(stroke
				(width 0.1)
				(type default)
			)
			(layer "F.Fab")
		)
		(pad "1" smd circle
			(at -0.40005 0)
			(size 0 0)
			(layers "F.Cu" "F.Mask" "F.Paste")
			(net "PRSNT_NIC0_FPGA_PCA9555_N")
		)
		(pad "2" smd circle
			(at 0.40005 0)
			(size 0 0)
			(layers "F.Cu" "F.Mask" "F.Paste")
			(net "PRSNT_NIC0_FPGA_R_N")
		)
	)
	(footprint ""
		(layer "F.Cu")
		(at 15.542768 -162.003994 -90)
		(property "Reference" "C839"
			(at 0 0 270)
			(layer "F.SilkS")
			(hide yes)
			(effects
				(font
					(size 1.27 1.27)
				)
			)
		)
		(property "Value" ""
			(at 0 0 270)
			(layer "F.Fab")
			(effects
				(font
					(size 1.27 1.27)
				)
			)
		)
		(duplicate_pad_numbers_are_jumpers no)
		(fp_line
			(start -0.7874 0.4064)
			(end -0.7874 -0.4064)
			(stroke
				(width 0.1524)
				(type default)
			)
			(layer "F.SilkS")
		)
		(fp_line
			(start 0.7874 0.4064)
			(end -0.7874 0.4064)
			(stroke
				(width 0.1524)
				(type default)
			)
			(layer "F.SilkS")
		)
		(fp_line
			(start -0.7874 -0.4064)
			(end 0.7874 -0.4064)
			(stroke
				(width 0.1524)
				(type default)
			)
			(layer "F.SilkS")
		)
		(fp_line
			(start 0.7874 -0.4064)
			(end 0.7874 0.4064)
			(stroke
				(width 0.1524)
				(type default)
			)
			(layer "F.SilkS")
		)
		(fp_line
			(start -0.67945 0.3048)
			(end -0.67945 -0.305054)
			(stroke
				(width 0.1)
				(type default)
			)
			(layer "F.Fab")
		)
		(fp_line
			(start -0.12065 0.3048)
			(end -0.67945 0.3048)
			(stroke
				(width 0.1)
				(type default)
			)
			(layer "F.Fab")
		)
		(fp_line
			(start 0.120396 0.3048)
			(end 0.120396 0.2794)
			(stroke
				(width 0.1)
				(type default)
			)
			(layer "F.Fab")
		)
		(fp_line
			(start 0.67945 0.3048)
			(end 0.120396 0.3048)
			(stroke
				(width 0.1)
				(type default)
			)
			(layer "F.Fab")
		)
		(fp_line
			(start -0.12065 0.2794)
			(end -0.12065 0.3048)
			(stroke
				(width 0.1)
				(type default)
			)
			(layer "F.Fab")
		)
		(fp_line
			(start 0.120396 0.2794)
			(end -0.12065 0.2794)
			(stroke
				(width 0.1)
				(type default)
			)
			(layer "F.Fab")
		)
		(fp_line
			(start -0.12065 -0.2794)
			(end 0.12065 -0.2794)
			(stroke
				(width 0.1)
				(type default)
			)
			(layer "F.Fab")
		)
		(fp_line
			(start 0.12065 -0.2794)
			(end 0.12065 -0.3048)
			(stroke
				(width 0.1)
				(type default)
			)
			(layer "F.Fab")
		)
		(fp_line
			(start 0.12065 -0.3048)
			(end 0.67945 -0.3048)
			(stroke
				(width 0.1)
				(type default)
			)
			(layer "F.Fab")
		)
		(fp_line
			(start 0.67945 -0.3048)
			(end 0.67945 0.3048)
			(stroke
				(width 0.1)
				(type default)
			)
			(layer "F.Fab")
		)
		(fp_line
			(start -0.67945 -0.305054)
			(end -0.12065 -0.305054)
			(stroke
				(width 0.1)
				(type default)
			)
			(layer "F.Fab")
		)
		(fp_line
			(start -0.12065 -0.305054)
			(end -0.12065 -0.2794)
			(stroke
				(width 0.1)
				(type default)
			)
			(layer "F.Fab")
		)
		(pad "1" smd circle
			(at -0.40005 0 270)
			(size 0 0)
			(layers "F.Cu" "F.Mask" "F.Paste")
			(net "GND")
		)
		(pad "2" smd circle
			(at 0.40005 0 270)
			(size 0 0)
			(layers "F.Cu" "F.Mask" "F.Paste")
			(net "P12V_NIC0_CO_EN")
		)
	)
)
